(kicad_pcb
	(version 20260206)
	(generator "pcbnew")
	(generator_version "10.0")
	(general
		(thickness 1.6)
		(legacy_teardrops no)
	)
	(paper "A4")
	(title_block
		(title "9054_F0T_PDB_BD_GPU_F_V04_1213_1550_OCP.brd")
		(comment 1 "Grand Teton / footprints 247-253 of 608")
	)
	(layers
		(0 "F.Cu" signal "TOP")
		(4 "In1.Cu" signal "GND")
		(6 "In2.Cu" signal "IN1")
		(8 "In3.Cu" signal "GND1")
		(10 "In4.Cu" signal "VCC")
		(12 "In5.Cu" signal "VCC1")
		(14 "In6.Cu" signal "GND2")
		(16 "In7.Cu" signal "IN2")
		(18 "In8.Cu" signal "GND3")
		(2 "B.Cu" signal "BOTTOM")
		(9 "F.Adhes" user "F.Adhesive")
		(11 "B.Adhes" user "B.Adhesive")
		(13 "F.Paste" user "Package Geometry/Pastemask Top")
		(15 "B.Paste" user "Package Geometry/Pastemask Bottom")
		(5 "F.SilkS" user "Ref Des/Silkscreen Top")
		(7 "B.SilkS" user "Ref Des/Silkscreen Bottom")
		(1 "F.Mask" user "Board Geometry/Soldermask Top")
		(3 "B.Mask" user "Board Geometry/Soldermask Bottom")
		(17 "Dwgs.User" user "User.Drawings")
		(19 "Cmts.User" user "User.Comments")
		(21 "Eco1.User" user "User.Eco1")
		(23 "Eco2.User" user "User.Eco2")
		(25 "Edge.Cuts" user "Board Geometry/Outline")
		(27 "Margin" user)
		(31 "F.CrtYd" user "Package Geometry/Place Bound Top")
		(29 "B.CrtYd" user "Package Geometry/Place Bound Bottom")
		(35 "F.Fab" user "Ref Des/Assembly Top")
		(33 "B.Fab" user "Ref Des/Assembly Bottom")
	)
	(footprint ""
		(layer "F.Cu")
		(at 451.612 -49.276 -90)
		(property "Reference" "R5915"
			(at 0 0 270)
			(layer "F.SilkS")
			(hide yes)
			(effects
				(font
					(size 1.27 1.27)
				)
			)
		)
		(property "Value" ""
			(at 0 0 270)
			(layer "F.Fab")
			(effects
				(font
					(size 1.27 1.27)
				)
			)
		)
		(duplicate_pad_numbers_are_jumpers no)
		(fp_line
			(start -0.7874 0.4064)
			(end -0.7874 -0.4064)
			(stroke
				(width 0.1524)
				(type default)
			)
			(layer "F.SilkS")
		)
		(fp_line
			(start 0.7874 0.4064)
			(end -0.7874 0.4064)
			(stroke
				(width 0.1524)
				(type default)
			)
			(layer "F.SilkS")
		)
		(fp_line
			(start -0.7874 -0.4064)
			(end 0.7874 -0.4064)
			(stroke
				(width 0.1524)
				(type default)
			)
			(layer "F.SilkS")
		)
		(fp_line
			(start 0.7874 -0.4064)
			(end 0.7874 0.4064)
			(stroke
				(width 0.1524)
				(type default)
			)
			(layer "F.SilkS")
		)
		(fp_line
			(start -0.67945 0.3048)
			(end -0.67945 -0.305054)
			(stroke
				(width 0.1)
				(type default)
			)
			(layer "F.Fab")
		)
		(fp_line
			(start -0.12065 0.3048)
			(end -0.67945 0.3048)
			(stroke
				(width 0.1)
				(type default)
			)
			(layer "F.Fab")
		)
		(fp_line
			(start 0.120396 0.3048)
			(end 0.120396 0.2794)
			(stroke
				(width 0.1)
				(type default)
			)
			(layer "F.Fab")
		)
		(fp_line
			(start 0.67945 0.3048)
			(end 0.120396 0.3048)
			(stroke
				(width 0.1)
				(type default)
			)
			(layer "F.Fab")
		)
		(fp_line
			(start -0.12065 0.2794)
			(end -0.12065 0.3048)
			(stroke
				(width 0.1)
				(type default)
			)
			(layer "F.Fab")
		)
		(fp_line
			(start 0.120396 0.2794)
			(end -0.12065 0.2794)
			(stroke
				(width 0.1)
				(type default)
			)
			(layer "F.Fab")
		)
		(fp_line
			(start -0.12065 -0.2794)
			(end 0.12065 -0.2794)
			(stroke
				(width 0.1)
				(type default)
			)
			(layer "F.Fab")
		)
		(fp_line
			(start 0.12065 -0.2794)
			(end 0.12065 -0.3048)
			(stroke
				(width 0.1)
				(type default)
			)
			(layer "F.Fab")
		)
		(fp_line
			(start 0.12065 -0.3048)
			(end 0.67945 -0.3048)
			(stroke
				(width 0.1)
				(type default)
			)
			(layer "F.Fab")
		)
		(fp_line
			(start 0.67945 -0.3048)
			(end 0.67945 0.3048)
			(stroke
				(width 0.1)
				(type default)
			)
			(layer "F.Fab")
		)
		(fp_line
			(start -0.67945 -0.305054)
			(end -0.12065 -0.305054)
			(stroke
				(width 0.1)
				(type default)
			)
			(layer "F.Fab")
		)
		(fp_line
			(start -0.12065 -0.305054)
			(end -0.12065 -0.2794)
			(stroke
				(width 0.1)
				(type default)
			)
			(layer "F.Fab")
		)
		(pad "1" smd circle
			(at -0.40005 0 270)
			(size 0 0)
			(layers "F.Cu" "F.Mask" "F.Paste")
			(net "PWRGD_P3V3_HPDB_R")
		)
		(pad "2" smd circle
			(at 0.40005 0 270)
			(size 0 0)
			(layers "F.Cu" "F.Mask" "F.Paste")
			(net "PWRGD_P3V3_HPDB")
		)
	)
	(footprint ""
		(layer "F.Cu")
		(at 140.79982 -37.9222 180)
		(property "Reference" "PR6993"
			(at 0 0 180)
			(layer "F.SilkS")
			(hide yes)
			(effects
				(font
					(size 1.27 1.27)
				)
			)
		)
		(property "Value" ""
			(at 0 0 180)
			(layer "F.Fab")
			(effects
				(font
					(size 1.27 1.27)
				)
			)
		)
		(duplicate_pad_numbers_are_jumpers no)
		(fp_line
			(start 1.2954 0.5842)
			(end -1.2954 0.5842)
			(stroke
				(width 0.1524)
				(type default)
			)
			(layer "F.SilkS")
		)
		(fp_line
			(start 1.2954 -0.5842)
			(end 1.2954 0.5842)
			(stroke
				(width 0.1524)
				(type default)
			)
			(layer "F.SilkS")
		)
		(fp_line
			(start -1.2954 0.5842)
			(end -1.2954 -0.5842)
			(stroke
				(width 0.1524)
				(type default)
			)
			(layer "F.SilkS")
		)
		(fp_line
			(start -1.2954 -0.5842)
			(end 1.2954 -0.5842)
			(stroke
				(width 0.1524)
				(type default)
			)
			(layer "F.SilkS")
		)
		(fp_line
			(start 1.1938 0.4064)
			(end 0.8636 0.4064)
			(stroke
				(width 0.1)
				(type default)
			)
			(layer "F.Fab")
		)
		(fp_line
			(start 1.1938 -0.406654)
			(end 1.1938 0.4064)
			(stroke
				(width 0.1)
				(type default)
			)
			(layer "F.Fab")
		)
		(fp_line
			(start 0.8636 0.4572)
			(end -0.8636 0.4572)
			(stroke
				(width 0.1)
				(type default)
			)
			(layer "F.Fab")
		)
		(fp_line
			(start 0.8636 0.4064)
			(end 0.8636 0.4572)
			(stroke
				(width 0.1)
				(type default)
			)
			(layer "F.Fab")
		)
		(fp_line
			(start 0.8636 -0.406654)
			(end 1.1938 -0.406654)
			(stroke
				(width 0.1)
				(type default)
			)
			(layer "F.Fab")
		)
		(fp_line
			(start 0.8636 -0.4572)
			(end 0.8636 -0.406654)
			(stroke
				(width 0.1)
				(type default)
			)
			(layer "F.Fab")
		)
		(fp_line
			(start -0.8636 0.4572)
			(end -0.8636 0.4318)
			(stroke
				(width 0.1)
				(type default)
			)
			(layer "F.Fab")
		)
		(fp_line
			(start -0.8636 0.4318)
			(end -0.8636 0.4064)
			(stroke
				(width 0.1)
				(type default)
			)
			(layer "F.Fab")
		)
		(fp_line
			(start -0.8636 0.4064)
			(end -1.1938 0.4064)
			(stroke
				(width 0.1)
				(type default)
			)
			(layer "F.Fab")
		)
		(fp_line
			(start -0.8636 -0.406654)
			(end -0.8636 -0.4572)
			(stroke
				(width 0.1)
				(type default)
			)
			(layer "F.Fab")
		)
		(fp_line
			(start -0.8636 -0.4572)
			(end 0.8636 -0.4572)
			(stroke
				(width 0.1)
				(type default)
			)
			(layer "F.Fab")
		)
		(fp_line
			(start -1.1938 0.4064)
			(end -1.1938 -0.406654)
			(stroke
				(width 0.1)
				(type default)
			)
			(layer "F.Fab")
		)
		(fp_line
			(start -1.1938 -0.406654)
			(end -0.8636 -0.406654)
			(stroke
				(width 0.1)
				(type default)
			)
			(layer "F.Fab")
		)
		(pad "1" smd rect
			(at -0.7366 0 90)
			(size 0.7112 0.8128)
			(layers "F.Cu" "F.Mask" "F.Paste")
			(net "P52V_HS2_4287_S2N")
		)
		(pad "2" smd rect
			(at 0.7366 0 90)
			(size 0.7112 0.8128)
			(layers "F.Cu" "F.Mask" "F.Paste")
			(net "P52V_HS2_SENSE_N_R2")
		)
	)
	(footprint ""
		(layer "F.Cu")
		(at 448.056 -41.148 90)
		(property "Reference" "R7"
			(at 0 0 90)
			(layer "F.SilkS")
			(hide yes)
			(effects
				(font
					(size 1.27 1.27)
				)
			)
		)
		(property "Value" ""
			(at 0 0 90)
			(layer "F.Fab")
			(effects
				(font
					(size 1.27 1.27)
				)
			)
		)
		(duplicate_pad_numbers_are_jumpers no)
		(fp_line
			(start 0.7874 -0.4064)
			(end 0.7874 0.4064)
			(stroke
				(width 0.1524)
				(type default)
			)
			(layer "F.SilkS")
		)
		(fp_line
			(start -0.7874 -0.4064)
			(end 0.7874 -0.4064)
			(stroke
				(width 0.1524)
				(type default)
			)
			(layer "F.SilkS")
		)
		(fp_line
			(start 0.7874 0.4064)
			(end -0.7874 0.4064)
			(stroke
				(width 0.1524)
				(type default)
			)
			(layer "F.SilkS")
		)
		(fp_line
			(start -0.7874 0.4064)
			(end -0.7874 -0.4064)
			(stroke
				(width 0.1524)
				(type default)
			)
			(layer "F.SilkS")
		)
		(fp_line
			(start -0.12065 -0.305054)
			(end -0.12065 -0.2794)
			(stroke
				(width 0.1)
				(type default)
			)
			(layer "F.Fab")
		)
		(fp_line
			(start -0.67945 -0.305054)
			(end -0.12065 -0.305054)
			(stroke
				(width 0.1)
				(type default)
			)
			(layer "F.Fab")
		)
		(fp_line
			(start 0.67945 -0.3048)
			(end 0.67945 0.3048)
			(stroke
				(width 0.1)
				(type default)
			)
			(layer "F.Fab")
		)
		(fp_line
			(start 0.12065 -0.3048)
			(end 0.67945 -0.3048)
			(stroke
				(width 0.1)
				(type default)
			)
			(layer "F.Fab")
		)
		(fp_line
			(start 0.12065 -0.2794)
			(end 0.12065 -0.3048)
			(stroke
				(width 0.1)
				(type default)
			)
			(layer "F.Fab")
		)
		(fp_line
			(start -0.12065 -0.2794)
			(end 0.12065 -0.2794)
			(stroke
				(width 0.1)
				(type default)
			)
			(layer "F.Fab")
		)
		(fp_line
			(start 0.120396 0.2794)
			(end -0.12065 0.2794)
			(stroke
				(width 0.1)
				(type default)
			)
			(layer "F.Fab")
		)
		(fp_line
			(start -0.12065 0.2794)
			(end -0.12065 0.3048)
			(stroke
				(width 0.1)
				(type default)
			)
			(layer "F.Fab")
		)
		(fp_line
			(start 0.67945 0.3048)
			(end 0.120396 0.3048)
			(stroke
				(width 0.1)
				(type default)
			)
			(layer "F.Fab")
		)
		(fp_line
			(start 0.120396 0.3048)
			(end 0.120396 0.2794)
			(stroke
				(width 0.1)
				(type default)
			)
			(layer "F.Fab")
		)
		(fp_line
			(start -0.12065 0.3048)
			(end -0.67945 0.3048)
			(stroke
				(width 0.1)
				(type default)
			)
			(layer "F.Fab")
		)
		(fp_line
			(start -0.67945 0.3048)
			(end -0.67945 -0.305054)
			(stroke
				(width 0.1)
				(type default)
			)
			(layer "F.Fab")
		)
		(pad "1" smd circle
			(at -0.40005 0 90)
			(size 0 0)
			(layers "F.Cu" "F.Mask" "F.Paste")
			(net "SMB_PDB_SDA")
		)
		(pad "2" smd circle
			(at 0.40005 0 90)
			(size 0 0)
			(layers "F.Cu" "F.Mask" "F.Paste")
			(net "SMB_PDB_MISC_SDA_R")
		)
	)
	(footprint ""
		(layer "F.Cu")
		(at 260.321298 -58.907426)
		(property "Reference" ""
			(at 0 0 0)
			(layer "F.SilkS")
			(hide yes)
			(effects
				(font
					(size 1.27 1.27)
				)
			)
		)
		(property "Value" ""
			(at 0 0 0)
			(layer "F.Fab")
			(effects
				(font
					(size 1.27 1.27)
				)
			)
		)
		(duplicate_pad_numbers_are_jumpers no)
		(pad "1" smd circle
			(at 0 0)
			(size 0.9906 0.9906)
			(layers "F.Cu" "F.Mask" "F.Paste")
			(net "Net_241")
		)
		(zone
			(layer "F.Cu")
			(hatch none 0.5)
			(connect_pads
				(clearance 0)
			)
			(min_thickness 0.25)
			(keepout
				(tracks not_allowed)
				(vias allowed)
				(pads allowed)
				(copperpour not_allowed)
				(footprints allowed)
			)
			(placement
				(enabled no)
				(sheetname "")
			)
			(fill
				(thermal_gap 0.5)
				(thermal_bridge_width 0.5)
				(island_removal_mode 0)
			)
			(polygon
				(pts
					(arc
						(start 261.946898 -58.907426)
						(mid 258.695698 -58.907426)
						(end 261.946898 -58.907426)
					)
				)
			)
		)
	)
	(footprint ""
		(layer "F.Cu")
		(at 167.767 -81.915 180)
		(property "Reference" "R5944"
			(at 0 0 180)
			(layer "F.SilkS")
			(hide yes)
			(effects
				(font
					(size 1.27 1.27)
				)
			)
		)
		(property "Value" ""
			(at 0 0 180)
			(layer "F.Fab")
			(effects
				(font
					(size 1.27 1.27)
				)
			)
		)
		(duplicate_pad_numbers_are_jumpers no)
		(fp_line
			(start 0.7874 0.4064)
			(end -0.7874 0.4064)
			(stroke
				(width 0.1524)
				(type default)
			)
			(layer "F.SilkS")
		)
		(fp_line
			(start 0.7874 -0.4064)
			(end 0.7874 0.4064)
			(stroke
				(width 0.1524)
				(type default)
			)
			(layer "F.SilkS")
		)
		(fp_line
			(start -0.7874 0.4064)
			(end -0.7874 -0.4064)
			(stroke
				(width 0.1524)
				(type default)
			)
			(layer "F.SilkS")
		)
		(fp_line
			(start -0.7874 -0.4064)
			(end 0.7874 -0.4064)
			(stroke
				(width 0.1524)
				(type default)
			)
			(layer "F.SilkS")
		)
		(fp_line
			(start 0.67945 0.3048)
			(end 0.120396 0.3048)
			(stroke
				(width 0.1)
				(type default)
			)
			(layer "F.Fab")
		)
		(fp_line
			(start 0.67945 -0.3048)
			(end 0.67945 0.3048)
			(stroke
				(width 0.1)
				(type default)
			)
			(layer "F.Fab")
		)
		(fp_line
			(start 0.12065 -0.2794)
			(end 0.12065 -0.3048)
			(stroke
				(width 0.1)
				(type default)
			)
			(layer "F.Fab")
		)
		(fp_line
			(start 0.12065 -0.3048)
			(end 0.67945 -0.3048)
			(stroke
				(width 0.1)
				(type default)
			)
			(layer "F.Fab")
		)
		(fp_line
			(start 0.120396 0.3048)
			(end 0.120396 0.2794)
			(stroke
				(width 0.1)
				(type default)
			)
			(layer "F.Fab")
		)
		(fp_line
			(start 0.120396 0.2794)
			(end -0.12065 0.2794)
			(stroke
				(width 0.1)
				(type default)
			)
			(layer "F.Fab")
		)
		(fp_line
			(start -0.12065 0.3048)
			(end -0.67945 0.3048)
			(stroke
				(width 0.1)
				(type default)
			)
			(layer "F.Fab")
		)
		(fp_line
			(start -0.12065 0.2794)
			(end -0.12065 0.3048)
			(stroke
				(width 0.1)
				(type default)
			)
			(layer "F.Fab")
		)
		(fp_line
			(start -0.12065 -0.2794)
			(end 0.12065 -0.2794)
			(stroke
				(width 0.1)
				(type default)
			)
			(layer "F.Fab")
		)
		(fp_line
			(start -0.12065 -0.305054)
			(end -0.12065 -0.2794)
			(stroke
				(width 0.1)
				(type default)
			)
			(layer "F.Fab")
		)
		(fp_line
			(start -0.67945 0.3048)
			(end -0.67945 -0.305054)
			(stroke
				(width 0.1)
				(type default)
			)
			(layer "F.Fab")
		)
		(fp_line
			(start -0.67945 -0.305054)
			(end -0.12065 -0.305054)
			(stroke
				(width 0.1)
				(type default)
			)
			(layer "F.Fab")
		)
		(pad "1" smd circle
			(at -0.40005 0 180)
			(size 0 0)
			(layers "F.Cu" "F.Mask" "F.Paste")
			(net "P3V3_AUX")
		)
		(pad "2" smd circle
			(at 0.40005 0 180)
			(size 0 0)
			(layers "F.Cu" "F.Mask" "F.Paste")
			(net "FM_HS2_EN_BUSBAR_BUF")
		)
	)
	(footprint ""
		(layer "F.Cu")
		(at 386.969 -29.083)
		(property "Reference" "PR99"
			(at 0 0 0)
			(layer "F.SilkS")
			(hide yes)
			(effects
				(font
					(size 1.27 1.27)
				)
			)
		)
		(property "Value" ""
			(at 0 0 0)
			(layer "F.Fab")
			(effects
				(font
					(size 1.27 1.27)
				)
			)
		)
		(duplicate_pad_numbers_are_jumpers no)
		(fp_line
			(start -0.7874 -0.4064)
			(end 0.7874 -0.4064)
			(stroke
				(width 0.1524)
				(type default)
			)
			(layer "F.SilkS")
		)
		(fp_line
			(start -0.7874 0.4064)
			(end -0.7874 -0.4064)
			(stroke
				(width 0.1524)
				(type default)
			)
			(layer "F.SilkS")
		)
		(fp_line
			(start 0.7874 -0.4064)
			(end 0.7874 0.4064)
			(stroke
				(width 0.1524)
				(type default)
			)
			(layer "F.SilkS")
		)
		(fp_line
			(start 0.7874 0.4064)
			(end -0.7874 0.4064)
			(stroke
				(width 0.1524)
				(type default)
			)
			(layer "F.SilkS")
		)
		(fp_line
			(start -0.67945 -0.305054)
			(end -0.12065 -0.305054)
			(stroke
				(width 0.1)
				(type default)
			)
			(layer "F.Fab")
		)
		(fp_line
			(start -0.67945 0.3048)
			(end -0.67945 -0.305054)
			(stroke
				(width 0.1)
				(type default)
			)
			(layer "F.Fab")
		)
		(fp_line
			(start -0.12065 -0.305054)
			(end -0.12065 -0.2794)
			(stroke
				(width 0.1)
				(type default)
			)
			(layer "F.Fab")
		)
		(fp_line
			(start -0.12065 -0.2794)
			(end 0.12065 -0.2794)
			(stroke
				(width 0.1)
				(type default)
			)
			(layer "F.Fab")
		)
		(fp_line
			(start -0.12065 0.2794)
			(end -0.12065 0.3048)
			(stroke
				(width 0.1)
				(type default)
			)
			(layer "F.Fab")
		)
		(fp_line
			(start -0.12065 0.3048)
			(end -0.67945 0.3048)
			(stroke
				(width 0.1)
				(type default)
			)
			(layer "F.Fab")
		)
		(fp_line
			(start 0.120396 0.2794)
			(end -0.12065 0.2794)
			(stroke
				(width 0.1)
				(type default)
			)
			(layer "F.Fab")
		)
		(fp_line
			(start 0.120396 0.3048)
			(end 0.120396 0.2794)
			(stroke
				(width 0.1)
				(type default)
			)
			(layer "F.Fab")
		)
		(fp_line
			(start 0.12065 -0.3048)
			(end 0.67945 -0.3048)
			(stroke
				(width 0.1)
				(type default)
			)
			(layer "F.Fab")
		)
		(fp_line
			(start 0.12065 -0.2794)
			(end 0.12065 -0.3048)
			(stroke
				(width 0.1)
				(type default)
			)
			(layer "F.Fab")
		)
		(fp_line
			(start 0.67945 -0.3048)
			(end 0.67945 0.3048)
			(stroke
				(width 0.1)
				(type default)
			)
			(layer "F.Fab")
		)
		(fp_line
			(start 0.67945 0.3048)
			(end 0.120396 0.3048)
			(stroke
				(width 0.1)
				(type default)
			)
			(layer "F.Fab")
		)
		(pad "1" smd circle
			(at -0.40005 0)
			(size 0 0)
			(layers "F.Cu" "F.Mask" "F.Paste")
			(net "P52V_HS1_EN_DISCHARGE_VBE")
		)
		(pad "2" smd circle
			(at 0.40005 0)
			(size 0 0)
			(layers "F.Cu" "F.Mask" "F.Paste")
			(net "P52V_HS1_EN_DISCHARGE_VBE_R")
		)
	)
	(footprint ""
		(layer "F.Cu")
		(at 450.041264 -85.870796 -90)
		(property "Reference" "PR114"
			(at 0 0 270)
			(layer "F.SilkS")
			(hide yes)
			(effects
				(font
					(size 1.27 1.27)
				)
			)
		)
		(property "Value" ""
			(at 0 0 270)
			(layer "F.Fab")
			(effects
				(font
					(size 1.27 1.27)
				)
			)
		)
		(duplicate_pad_numbers_are_jumpers no)
		(fp_line
			(start -0.7874 0.4064)
			(end -0.7874 -0.4064)
			(stroke
				(width 0.1524)
				(type default)
			)
			(layer "F.SilkS")
		)
		(fp_line
			(start 0.7874 0.4064)
			(end -0.7874 0.4064)
			(stroke
				(width 0.1524)
				(type default)
			)
			(layer "F.SilkS")
		)
		(fp_line
			(start -0.7874 -0.4064)
			(end 0.7874 -0.4064)
			(stroke
				(width 0.1524)
				(type default)
			)
			(layer "F.SilkS")
		)
		(fp_line
			(start 0.7874 -0.4064)
			(end 0.7874 0.4064)
			(stroke
				(width 0.1524)
				(type default)
			)
			(layer "F.SilkS")
		)
		(fp_line
			(start -0.67945 0.3048)
			(end -0.67945 -0.305054)
			(stroke
				(width 0.1)
				(type default)
			)
			(layer "F.Fab")
		)
		(fp_line
			(start -0.12065 0.3048)
			(end -0.67945 0.3048)
			(stroke
				(width 0.1)
				(type default)
			)
			(layer "F.Fab")
		)
		(fp_line
			(start 0.120396 0.3048)
			(end 0.120396 0.2794)
			(stroke
				(width 0.1)
				(type default)
			)
			(layer "F.Fab")
		)
		(fp_line
			(start 0.67945 0.3048)
			(end 0.120396 0.3048)
			(stroke
				(width 0.1)
				(type default)
			)
			(layer "F.Fab")
		)
		(fp_line
			(start -0.12065 0.2794)
			(end -0.12065 0.3048)
			(stroke
				(width 0.1)
				(type default)
			)
			(layer "F.Fab")
		)
		(fp_line
			(start 0.120396 0.2794)
			(end -0.12065 0.2794)
			(stroke
				(width 0.1)
				(type default)
			)
			(layer "F.Fab")
		)
		(fp_line
			(start -0.12065 -0.2794)
			(end 0.12065 -0.2794)
			(stroke
				(width 0.1)
				(type default)
			)
			(layer "F.Fab")
		)
		(fp_line
			(start 0.12065 -0.2794)
			(end 0.12065 -0.3048)
			(stroke
				(width 0.1)
				(type default)
			)
			(layer "F.Fab")
		)
		(fp_line
			(start 0.12065 -0.3048)
			(end 0.67945 -0.3048)
			(stroke
				(width 0.1)
				(type default)
			)
			(layer "F.Fab")
		)
		(fp_line
			(start 0.67945 -0.3048)
			(end 0.67945 0.3048)
			(stroke
				(width 0.1)
				(type default)
			)
			(layer "F.Fab")
		)
		(fp_line
			(start -0.67945 -0.305054)
			(end -0.12065 -0.305054)
			(stroke
				(width 0.1)
				(type default)
			)
			(layer "F.Fab")
		)
		(fp_line
			(start -0.12065 -0.305054)
			(end -0.12065 -0.2794)
			(stroke
				(width 0.1)
				(type default)
			)
			(layer "F.Fab")
		)
		(pad "1" smd circle
			(at -0.40005 0 270)
			(size 0 0)
			(layers "F.Cu" "F.Mask" "F.Paste")
			(net "P3V3_HPDB_FB")
		)
		(pad "2" smd circle
			(at 0.40005 0 270)
			(size 0 0)
			(layers "F.Cu" "F.Mask" "F.Paste")
			(net "GND")
		)
	)
)
